(kicad_pcb
	(version 20260206)
	(generator "pcbnew")
	(generator_version "10.0")
	(general
		(thickness 1.21888)
		(legacy_teardrops no)
	)
	(paper "A4")
	(title_block
		(title "timecard-v9 — TimeCard-DC-V9_EXP.PcbDoc")
		(comment 1 "Time Appliance Project (Time Card) / footprints 241-243 of 402")
	)
	(layers
		(0 "F.Cu" signal "TOP")
		(4 "In1.Cu" signal "SGND")
		(6 "In2.Cu" signal "IN1")
		(8 "In3.Cu" signal "IN2")
		(10 "In4.Cu" signal "SGND1")
		(2 "B.Cu" signal "BOTTOM")
		(9 "F.Adhes" user "F.Adhesive")
		(11 "B.Adhes" user "B.Adhesive")
		(13 "F.Paste" user "Top Paste")
		(15 "B.Paste" user "Bottom Paste")
		(5 "F.SilkS" user "Top Overlay")
		(7 "B.SilkS" user "Bottom Overlay")
		(1 "F.Mask" user "Top Solder")
		(3 "B.Mask" user "Bottom Solder")
		(17 "Dwgs.User" user "User.Drawings")
		(19 "Cmts.User" user "User.Comments")
		(21 "Eco1.User" user "User.Eco1")
		(23 "Eco2.User" user "User.Eco2")
		(25 "Edge.Cuts" user)
		(27 "Margin" user)
		(31 "F.CrtYd" user "Top Courtyard")
		(29 "B.CrtYd" user "Bottom Courtyard")
		(35 "F.Fab" user "Top Component Center")
		(33 "B.Fab" user "Bottom Component Center")
	)
	(footprint "FPGA_CONN:SingleFPGAConn"
		(locked yes)
		(layer "F.Cu")
		(at 171.29647 138.90823 90)
		(property "Reference" "J37"
			(at -0.39436 -23.455119 90)
			(unlocked yes)
			(layer "F.SilkS")
			(effects
				(font
					(size 0.762 0.762)
					(thickness 0.2286)
				)
			)
		)
		(property "Value" "Single FPGA Conn"
			(at 9.25452 3.621231 90)
			(unlocked yes)
			(layer "F.SilkS")
			(hide yes)
			(effects
				(font
					(size 0.762 0.762)
					(thickness 0.2286)
				)
			)
		)
		(sheetname "07-FPGA")
		(sheetfile "07-FPGA.kicad_sch")
		(duplicate_pad_numbers_are_jumpers no)
		(fp_line
			(start 1.40005 -21.24989)
			(end 2 -20.69998)
			(stroke
				(width 0.15011)
				(type solid)
			)
			(layer "F.SilkS")
		)
		(fp_line
			(start -1.40005 -21.24989)
			(end 1.40005 -21.24989)
			(stroke
				(width 0.15011)
				(type solid)
			)
			(layer "F.SilkS")
		)
		(fp_line
			(start -1.40005 -21.24989)
			(end -1.40005 -20.69998)
			(stroke
				(width 0.15011)
				(type solid)
			)
			(layer "F.SilkS")
		)
		(fp_line
			(start 2 -20.69998)
			(end 2 -20.03298)
			(stroke
				(width 0.15011)
				(type solid)
			)
			(layer "F.SilkS")
		)
		(fp_line
			(start -2 -20.69998)
			(end -1.40005 -20.69998)
			(stroke
				(width 0.15011)
				(type solid)
			)
			(layer "F.SilkS")
		)
		(fp_line
			(start -2 -20.69998)
			(end -2 -20.03298)
			(stroke
				(width 0.15011)
				(type solid)
			)
			(layer "F.SilkS")
		)
		(fp_line
			(start 2 0.03302)
			(end 2 0.70003)
			(stroke
				(width 0.15011)
				(type solid)
			)
			(layer "F.SilkS")
		)
		(fp_line
			(start -2 0.03302)
			(end -2 0.70003)
			(stroke
				(width 0.15011)
				(type solid)
			)
			(layer "F.SilkS")
		)
		(fp_line
			(start 2 0.70003)
			(end 1.40005 1.24994)
			(stroke
				(width 0.15011)
				(type solid)
			)
			(layer "F.SilkS")
		)
		(fp_line
			(start -1.40005 0.70003)
			(end -1.40005 1.24994)
			(stroke
				(width 0.15011)
				(type solid)
			)
			(layer "F.SilkS")
		)
		(fp_line
			(start -2 0.70003)
			(end -1.40005 0.70003)
			(stroke
				(width 0.15011)
				(type solid)
			)
			(layer "F.SilkS")
		)
		(fp_line
			(start -1.40005 1.24994)
			(end 1.40005 1.24994)
			(stroke
				(width 0.15011)
				(type solid)
			)
			(layer "F.SilkS")
		)
		(fp_circle
			(center 3.5052 -0.22453)
			(end 3.70535 -0.22453)
			(stroke
				(width 0.40005)
				(type solid)
			)
			(fill no)
			(layer "F.SilkS")
		)
		(pad "1" smd rect
			(at 2.02489 -0.24993 90)
			(size 1.54991 0.24994)
			(layers "F.Cu" "F.Mask" "F.Paste")
		)
		(pad "2" smd rect
			(at -2.02489 -0.24993 90)
			(size 1.54991 0.24994)
			(layers "F.Cu" "F.Mask" "F.Paste")
		)
		(pad "3" smd rect
			(at 2.02489 -0.75006 90)
			(size 1.54991 0.24994)
			(layers "F.Cu" "F.Mask" "F.Paste")
		)
		(pad "4" smd rect
			(at -2.02489 -0.75006 90)
			(size 1.54991 0.24994)
			(layers "F.Cu" "F.Mask" "F.Paste")
		)
		(pad "5" smd rect
			(at 2.02489 -1.24993 90)
			(size 1.54991 0.24994)
			(layers "F.Cu" "F.Mask" "F.Paste")
		)
		(pad "6" smd rect
			(at -2.02489 -1.24993 90)
			(size 1.54991 0.24994)
			(layers "F.Cu" "F.Mask" "F.Paste")
		)
		(pad "7" smd rect
			(at 2.02489 -1.75006 90)
			(size 1.54991 0.24994)
			(layers "F.Cu" "F.Mask" "F.Paste")
		)
		(pad "8" smd rect
			(at -2.02489 -1.75006 90)
			(size 1.54991 0.24994)
			(layers "F.Cu" "F.Mask" "F.Paste")
		)
		(pad "9" smd rect
			(at 2.02489 -2.24993 90)
			(size 1.54991 0.24994)
			(layers "F.Cu" "F.Mask" "F.Paste")
			(net "GND")
		)
		(pad "10" smd rect
			(at -2.02489 -2.24993 90)
			(size 1.54991 0.24994)
			(layers "F.Cu" "F.Mask" "F.Paste")
			(net "GND")
		)
		(pad "11" smd rect
			(at 2.02489 -2.75005 90)
			(size 1.54991 0.24994)
			(layers "F.Cu" "F.Mask" "F.Paste")
		)
		(pad "12" smd rect
			(at -2.02489 -2.75005 90)
			(size 1.54991 0.24994)
			(layers "F.Cu" "F.Mask" "F.Paste")
			(net "PCIE_TX2_P")
		)
		(pad "13" smd rect
			(at 2.02489 -3.24993 90)
			(size 1.54991 0.24994)
			(layers "F.Cu" "F.Mask" "F.Paste")
		)
		(pad "14" smd rect
			(at -2.02489 -3.24993 90)
			(size 1.54991 0.24994)
			(layers "F.Cu" "F.Mask" "F.Paste")
			(net "PCIE_TX2_N")
		)
		(pad "15" smd rect
			(at 2.02489 -3.75005 90)
			(size 1.54991 0.24994)
			(layers "F.Cu" "F.Mask" "F.Paste")
			(net "GND")
		)
		(pad "16" smd rect
			(at -2.02489 -3.75005 90)
			(size 1.54991 0.24994)
			(layers "F.Cu" "F.Mask" "F.Paste")
		)
		(pad "17" smd rect
			(at 2.02489 -4.24992 90)
			(size 1.54991 0.24994)
			(layers "F.Cu" "F.Mask" "F.Paste")
			(net "PCIE_TX3_P")
		)
		(pad "18" smd rect
			(at -2.02489 -4.24992 90)
			(size 1.54991 0.24994)
			(layers "F.Cu" "F.Mask" "F.Paste")
			(net "PCIE_RX2_P")
		)
		(pad "19" smd rect
			(at 2.02489 -4.75005 90)
			(size 1.54991 0.24994)
			(layers "F.Cu" "F.Mask" "F.Paste")
			(net "PCIE_TX3_N")
		)
		(pad "20" smd rect
			(at -2.02489 -4.75005 90)
			(size 1.54991 0.24994)
			(layers "F.Cu" "F.Mask" "F.Paste")
			(net "PCIE_RX2_N")
		)
		(pad "21" smd rect
			(at 2.02489 -5.24992 90)
			(size 1.54991 0.24994)
			(layers "F.Cu" "F.Mask" "F.Paste")
			(net "GND")
		)
		(pad "22" smd rect
			(at -2.02489 -5.24992 90)
			(size 1.54991 0.24994)
			(layers "F.Cu" "F.Mask" "F.Paste")
		)
		(pad "23" smd rect
			(at 2.02489 -5.75005 90)
			(size 1.54991 0.24994)
			(layers "F.Cu" "F.Mask" "F.Paste")
			(net "PCIE_RX3_P")
		)
		(pad "24" smd rect
			(at -2.02489 -5.75005 90)
			(size 1.54991 0.24994)
			(layers "F.Cu" "F.Mask" "F.Paste")
			(net "PCIE_TX1_P")
		)
		(pad "25" smd rect
			(at 2.02489 -6.24992 90)
			(size 1.54991 0.24994)
			(layers "F.Cu" "F.Mask" "F.Paste")
			(net "PCIE_RX3_N")
		)
		(pad "26" smd rect
			(at -2.02489 -6.24992 90)
			(size 1.54991 0.24994)
			(layers "F.Cu" "F.Mask" "F.Paste")
			(net "PCIE_TX1_N")
		)
		(pad "27" smd rect
			(at 2.02489 -6.75005 90)
			(size 1.54991 0.24994)
			(layers "F.Cu" "F.Mask" "F.Paste")
			(net "GND")
		)
		(pad "28" smd rect
			(at -2.02489 -6.75005 90)
			(size 1.54991 0.24994)
			(layers "F.Cu" "F.Mask" "F.Paste")
		)
		(pad "29" smd rect
			(at 2.02489 -7.24992 90)
			(size 1.54991 0.24994)
			(layers "F.Cu" "F.Mask" "F.Paste")
			(net "PCIE_TX0_P")
		)
		(pad "30" smd rect
			(at -2.02489 -7.24992 90)
			(size 1.54991 0.24994)
			(layers "F.Cu" "F.Mask" "F.Paste")
			(net "PCIE_RX1_P")
		)
		(pad "31" smd rect
			(at 2.02489 -7.75004 90)
			(size 1.54991 0.24994)
			(layers "F.Cu" "F.Mask" "F.Paste")
			(net "PCIE_TX0_N")
		)
		(pad "32" smd rect
			(at -2.02489 -7.75004 90)
			(size 1.54991 0.24994)
			(layers "F.Cu" "F.Mask" "F.Paste")
			(net "PCIE_RX1_N")
		)
		(pad "33" smd rect
			(at 2.02489 -8.24992 90)
			(size 1.54991 0.24994)
			(layers "F.Cu" "F.Mask" "F.Paste")
			(net "GND")
		)
		(pad "34" smd rect
			(at -2.02489 -8.24992 90)
			(size 1.54991 0.24994)
			(layers "F.Cu" "F.Mask" "F.Paste")
		)
		(pad "35" smd rect
			(at 2.02489 -8.75004 90)
			(size 1.54991 0.24994)
			(layers "F.Cu" "F.Mask" "F.Paste")
			(net "PCIE_RX0_P")
		)
		(pad "36" smd rect
			(at -2.02489 -8.75004 90)
			(size 1.54991 0.24994)
			(layers "F.Cu" "F.Mask" "F.Paste")
			(net "PCIE_CLK_P")
		)
		(pad "37" smd rect
			(at 2.02489 -9.24991 90)
			(size 1.54991 0.24994)
			(layers "F.Cu" "F.Mask" "F.Paste")
			(net "PCIE_RX0_N")
		)
		(pad "38" smd rect
			(at -2.02489 -9.24991 90)
			(size 1.54991 0.24994)
			(layers "F.Cu" "F.Mask" "F.Paste")
			(net "PCIE_CLK_N")
		)
		(pad "39" smd rect
			(at 2.02489 -9.75004 90)
			(size 1.54991 0.24994)
			(layers "F.Cu" "F.Mask" "F.Paste")
			(net "GND")
		)
		(pad "40" smd rect
			(at -2.02489 -9.75004 90)
			(size 1.54991 0.24994)
			(layers "F.Cu" "F.Mask" "F.Paste")
			(net "GND")
		)
		(pad "41" smd rect
			(at 2.02489 -10.24991 90)
			(size 1.54991 0.24994)
			(layers "F.Cu" "F.Mask" "F.Paste")
		)
		(pad "42" smd rect
			(at -2.02489 -10.24991 90)
			(size 1.54991 0.24994)
			(layers "F.Cu" "F.Mask" "F.Paste")
		)
		(pad "43" smd rect
			(at 2.02489 -10.75004 90)
			(size 1.54991 0.24994)
			(layers "F.Cu" "F.Mask" "F.Paste")
		)
		(pad "44" smd rect
			(at -2.02489 -10.75004 90)
			(size 1.54991 0.24994)
			(layers "F.Cu" "F.Mask" "F.Paste")
		)
		(pad "45" smd rect
			(at 2.02489 -11.24991 90)
			(size 1.54991 0.24994)
			(layers "F.Cu" "F.Mask" "F.Paste")
		)
		(pad "46" smd rect
			(at -2.02489 -11.24991 90)
			(size 1.54991 0.24994)
			(layers "F.Cu" "F.Mask" "F.Paste")
		)
		(pad "47" smd rect
			(at 2.02489 -11.75004 90)
			(size 1.54991 0.24994)
			(layers "F.Cu" "F.Mask" "F.Paste")
		)
		(pad "48" smd rect
			(at -2.02489 -11.75004 90)
			(size 1.54991 0.24994)
			(layers "F.Cu" "F.Mask" "F.Paste")
		)
		(pad "49" smd rect
			(at 2.02489 -12.24991 90)
			(size 1.54991 0.24994)
			(layers "F.Cu" "F.Mask" "F.Paste")
			(net "GND")
		)
		(pad "50" smd rect
			(at -2.02489 -12.24991 90)
			(size 1.54991 0.24994)
			(layers "F.Cu" "F.Mask" "F.Paste")
			(net "GND")
		)
		(pad "51" smd rect
			(at 2.02489 -12.75003 90)
			(size 1.54991 0.24994)
			(layers "F.Cu" "F.Mask" "F.Paste")
		)
		(pad "52" smd rect
			(at -2.02489 -12.75003 90)
			(size 1.54991 0.24994)
			(layers "F.Cu" "F.Mask" "F.Paste")
		)
		(pad "53" smd rect
			(at 2.02489 -13.24991 90)
			(size 1.54991 0.24994)
			(layers "F.Cu" "F.Mask" "F.Paste")
		)
		(pad "54" smd rect
			(at -2.02489 -13.24991 90)
			(size 1.54991 0.24994)
			(layers "F.Cu" "F.Mask" "F.Paste")
		)
		(pad "55" smd rect
			(at 2.02489 -13.75003 90)
			(size 1.54991 0.24994)
			(layers "F.Cu" "F.Mask" "F.Paste")
		)
		(pad "56" smd rect
			(at -2.02489 -13.75003 90)
			(size 1.54991 0.24994)
			(layers "F.Cu" "F.Mask" "F.Paste")
		)
		(pad "57" smd rect
			(at 2.02489 -14.2499 90)
			(size 1.54991 0.24994)
			(layers "F.Cu" "F.Mask" "F.Paste")
		)
		(pad "58" smd rect
			(at -2.02489 -14.2499 90)
			(size 1.54991 0.24994)
			(layers "F.Cu" "F.Mask" "F.Paste")
		)
		(pad "59" smd rect
			(at 2.02489 -14.75003 90)
			(size 1.54991 0.24994)
			(layers "F.Cu" "F.Mask" "F.Paste")
			(net "GND")
		)
		(pad "60" smd rect
			(at -2.02489 -14.75003 90)
			(size 1.54991 0.24994)
			(layers "F.Cu" "F.Mask" "F.Paste")
			(net "GND")
		)
		(pad "61" smd rect
			(at 2.02489 -15.2499 90)
			(size 1.54991 0.24994)
			(layers "F.Cu" "F.Mask" "F.Paste")
		)
		(pad "62" smd rect
			(at -2.02489 -15.2499 90)
			(size 1.54991 0.24994)
			(layers "F.Cu" "F.Mask" "F.Paste")
		)
		(pad "63" smd rect
			(at 2.02489 -15.75003 90)
			(size 1.54991 0.24994)
			(layers "F.Cu" "F.Mask" "F.Paste")
		)
		(pad "64" smd rect
			(at -2.02489 -15.75003 90)
			(size 1.54991 0.24994)
			(layers "F.Cu" "F.Mask" "F.Paste")
		)
		(pad "65" smd rect
			(at 2.02489 -16.2499 90)
			(size 1.54991 0.24994)
			(layers "F.Cu" "F.Mask" "F.Paste")
		)
		(pad "66" smd rect
			(at -2.02489 -16.2499 90)
			(size 1.54991 0.24994)
			(layers "F.Cu" "F.Mask" "F.Paste")
		)
		(pad "67" smd rect
			(at 2.02489 -16.75003 90)
			(size 1.54991 0.24994)
			(layers "F.Cu" "F.Mask" "F.Paste")
		)
		(pad "68" smd rect
			(at -2.02489 -16.75003 90)
			(size 1.54991 0.24994)
			(layers "F.Cu" "F.Mask" "F.Paste")
		)
		(pad "69" smd rect
			(at 2.02489 -17.2499 90)
			(size 1.54991 0.24994)
			(layers "F.Cu" "F.Mask" "F.Paste")
			(net "GND")
		)
		(pad "70" smd rect
			(at -2.02489 -17.2499 90)
			(size 1.54991 0.24994)
			(layers "F.Cu" "F.Mask" "F.Paste")
			(net "GND")
		)
		(pad "71" smd rect
			(at 2.02489 -17.75002 90)
			(size 1.54991 0.24994)
			(layers "F.Cu" "F.Mask" "F.Paste")
		)
		(pad "72" smd rect
			(at -2.02489 -17.75002 90)
			(size 1.54991 0.24994)
			(layers "F.Cu" "F.Mask" "F.Paste")
		)
		(pad "73" smd rect
			(at 2.02489 -18.2499 90)
			(size 1.54991 0.24994)
			(layers "F.Cu" "F.Mask" "F.Paste")
		)
		(pad "74" smd rect
			(at -2.02489 -18.2499 90)
			(size 1.54991 0.24994)
			(layers "F.Cu" "F.Mask" "F.Paste")
		)
		(pad "75" smd rect
			(at 2.02489 -18.75002 90)
			(size 1.54991 0.24994)
			(layers "F.Cu" "F.Mask" "F.Paste")
		)
		(pad "76" smd rect
			(at -2.02489 -18.75002 90)
			(size 1.54991 0.24994)
			(layers "F.Cu" "F.Mask" "F.Paste")
		)
		(pad "77" smd rect
			(at 2.02489 -19.24989 90)
			(size 1.54991 0.24994)
			(layers "F.Cu" "F.Mask" "F.Paste")
		)
		(pad "78" smd rect
			(at -2.02489 -19.24989 90)
			(size 1.54991 0.24994)
			(layers "F.Cu" "F.Mask" "F.Paste")
		)
		(pad "79" smd rect
			(at 2.02489 -19.75002 90)
			(size 1.54991 0.24994)
			(layers "F.Cu" "F.Mask" "F.Paste")
		)
		(pad "80" smd rect
			(at -2.02489 -19.75002 90)
			(size 1.54991 0.24994)
			(layers "F.Cu" "F.Mask" "F.Paste")
		)
		(pad "81" smd rect
			(at 0.01135 1.17626 90)
			(size 1.70002 1.35001)
			(layers "F.Cu" "F.Mask" "F.Paste")
		)
		(pad "82" thru_hole circle
			(at 0 0 90)
			(size 0.55016 0.55016)
			(drill 0.55016)
			(layers "*.Cu" "*.Mask")
			(remove_unused_layers no)
			(thermal_bridge_angle 90)
		)
		(pad "83" thru_hole circle
			(at 0 -19.99996 90)
			(size 0.55016 0.55016)
			(drill 0.55016)
			(layers "*.Cu" "*.Mask")
			(remove_unused_layers no)
			(thermal_bridge_angle 90)
		)
		(pad "84" smd rect
			(at 0.01135 -21.17374 90)
			(size 1.70002 1.35001)
			(layers "F.Cu" "F.Mask" "F.Paste")
		)
	)
	(footprint "Resistors:RESC1005X04N"
		(layer "F.Cu")
		(at 105.8216 143.5162)
		(property "Reference" "R23"
			(at -3.3 0.493345 0)
			(unlocked yes)
			(layer "F.SilkS")
			(effects
				(font
					(size 0.762 0.762)
					(thickness 0.2286)
				)
				(justify left bottom)
			)
		)
		(property "Value" "ERJ-2GE0R00X"
			(at -0.2413 3.331845 0)
			(unlocked yes)
			(layer "F.SilkS")
			(hide yes)
			(effects
				(font
					(size 0.762 0.762)
					(thickness 0.2286)
				)
				(justify left bottom)
			)
		)
		(sheetname "04-PCIe_JTAG")
		(sheetfile "04-PCIe_JTAG.kicad_sch")
		(duplicate_pad_numbers_are_jumpers no)
		(pad "1" smd rect
			(at -0.425 0 90)
			(size 0.6 0.65)
			(layers "F.Cu" "F.Mask" "F.Paste")
			(net "PRSNT")
		)
		(pad "2" smd rect
			(at 0.425 0 90)
			(size 0.6 0.65)
			(layers "F.Cu" "F.Mask" "F.Paste")
			(net "NetP2_B17")
		)
	)
	(footprint "Vault:RESC1005X40X25NL05T05"
		(layer "F.Cu")
		(at 153.4216 127.1162)
		(property "Reference" "R102"
			(at -0.2714 -1.173069 0)
			(unlocked yes)
			(layer "F.SilkS")
			(effects
				(font
					(size 0.762 0.762)
					(thickness 0.2286)
				)
			)
		)
		(property "Value" "DNI_27_1%_0402"
			(at -2.732271 10.296375 270)
			(unlocked yes)
			(layer "F.SilkS")
			(hide yes)
			(effects
				(font
					(size 0.762 0.762)
					(thickness 0.2286)
				)
			)
		)
		(sheetname "09-USBUart_PPSMUX_UARTMUX")
		(sheetfile "09-USBUart_PPSMUX_UARTMUX.kicad_sch")
		(duplicate_pad_numbers_are_jumpers no)
		(pad "1" smd rect
			(at -0.45 0 90)
			(size 0.55 0.55)
			(layers "F.Cu" "F.Mask" "F.Paste")
			(net "GPS2_TX_FPGA")
		)
		(pad "2" smd rect
			(at 0.45 0 90)
			(size 0.55 0.55)
			(layers "F.Cu" "F.Mask" "F.Paste")
			(net "GPS2_TX")
		)
	)
)
